(kicad_pcb
	(version 20260206)
	(generator "pcbnew")
	(generator_version "10.0")
	(general
		(thickness 1.6)
		(legacy_teardrops no)
	)
	(paper "A4")
	(title_block
		(title "03242023_DA0F0TMBIJ0_F0T_Motherboard_J_brd_V01_OCP.brd")
		(comment 1 "Grand Teton / footprints 2486-2492 of 6105")
	)
	(layers
		(0 "F.Cu" signal "TOP")
		(4 "In1.Cu" signal "GND")
		(6 "In2.Cu" signal "IN1")
		(8 "In3.Cu" signal "GND1")
		(10 "In4.Cu" signal "IN2")
		(12 "In5.Cu" signal "GND2")
		(14 "In6.Cu" signal "IN3")
		(16 "In7.Cu" signal "GND3")
		(18 "In8.Cu" signal "VCC")
		(20 "In9.Cu" signal "VCC1")
		(22 "In10.Cu" signal "GND4")
		(24 "In11.Cu" signal "IN4")
		(26 "In12.Cu" signal "GND5")
		(28 "In13.Cu" signal "IN5")
		(30 "In14.Cu" signal "GND6")
		(32 "In15.Cu" signal "IN6")
		(34 "In16.Cu" signal "GND7")
		(2 "B.Cu" signal "BOTTOM")
		(9 "F.Adhes" user "F.Adhesive")
		(11 "B.Adhes" user "B.Adhesive")
		(13 "F.Paste" user "Package Geometry/Pastemask Top")
		(15 "B.Paste" user "Package Geometry/Pastemask Bottom")
		(5 "F.SilkS" user "Ref Des/Silkscreen Top")
		(7 "B.SilkS" user "Ref Des/Silkscreen Bottom")
		(1 "F.Mask" user "Board Geometry/Soldermask Top")
		(3 "B.Mask" user "Board Geometry/Soldermask Bottom")
		(17 "Dwgs.User" user "User.Drawings")
		(19 "Cmts.User" user "User.Comments")
		(21 "Eco1.User" user "User.Eco1")
		(23 "Eco2.User" user "User.Eco2")
		(25 "Edge.Cuts" user "Board Geometry/Outline")
		(27 "Margin" user)
		(31 "F.CrtYd" user "Package Geometry/Place Bound Top")
		(29 "B.CrtYd" user "Package Geometry/Place Bound Bottom")
		(35 "F.Fab" user "Ref Des/Assembly Top")
		(33 "B.Fab" user "Ref Des/Assembly Bottom")
	)
	(footprint ""
		(layer "F.Cu")
		(at 29.93009 -391.65149)
		(property "Reference" "R3386"
			(at 0 0 0)
			(layer "F.SilkS")
			(hide yes)
			(effects
				(font
					(size 1.27 1.27)
				)
			)
		)
		(property "Value" ""
			(at 0 0 0)
			(layer "F.Fab")
			(effects
				(font
					(size 1.27 1.27)
				)
			)
		)
		(duplicate_pad_numbers_are_jumpers no)
		(fp_line
			(start -0.7874 -0.4064)
			(end 0.7874 -0.4064)
			(stroke
				(width 0.1524)
				(type default)
			)
			(layer "F.SilkS")
		)
		(fp_line
			(start -0.7874 0.4064)
			(end -0.7874 -0.4064)
			(stroke
				(width 0.1524)
				(type default)
			)
			(layer "F.SilkS")
		)
		(fp_line
			(start 0.7874 -0.4064)
			(end 0.7874 0.4064)
			(stroke
				(width 0.1524)
				(type default)
			)
			(layer "F.SilkS")
		)
		(fp_line
			(start 0.7874 0.4064)
			(end -0.7874 0.4064)
			(stroke
				(width 0.1524)
				(type default)
			)
			(layer "F.SilkS")
		)
		(fp_line
			(start -0.67945 -0.305054)
			(end -0.12065 -0.305054)
			(stroke
				(width 0.1)
				(type default)
			)
			(layer "F.Fab")
		)
		(fp_line
			(start -0.67945 0.3048)
			(end -0.67945 -0.305054)
			(stroke
				(width 0.1)
				(type default)
			)
			(layer "F.Fab")
		)
		(fp_line
			(start -0.12065 -0.305054)
			(end -0.12065 -0.2794)
			(stroke
				(width 0.1)
				(type default)
			)
			(layer "F.Fab")
		)
		(fp_line
			(start -0.12065 -0.2794)
			(end 0.12065 -0.2794)
			(stroke
				(width 0.1)
				(type default)
			)
			(layer "F.Fab")
		)
		(fp_line
			(start -0.12065 0.2794)
			(end -0.12065 0.3048)
			(stroke
				(width 0.1)
				(type default)
			)
			(layer "F.Fab")
		)
		(fp_line
			(start -0.12065 0.3048)
			(end -0.67945 0.3048)
			(stroke
				(width 0.1)
				(type default)
			)
			(layer "F.Fab")
		)
		(fp_line
			(start 0.120396 0.2794)
			(end -0.12065 0.2794)
			(stroke
				(width 0.1)
				(type default)
			)
			(layer "F.Fab")
		)
		(fp_line
			(start 0.120396 0.3048)
			(end 0.120396 0.2794)
			(stroke
				(width 0.1)
				(type default)
			)
			(layer "F.Fab")
		)
		(fp_line
			(start 0.12065 -0.3048)
			(end 0.67945 -0.3048)
			(stroke
				(width 0.1)
				(type default)
			)
			(layer "F.Fab")
		)
		(fp_line
			(start 0.12065 -0.2794)
			(end 0.12065 -0.3048)
			(stroke
				(width 0.1)
				(type default)
			)
			(layer "F.Fab")
		)
		(fp_line
			(start 0.67945 -0.3048)
			(end 0.67945 0.3048)
			(stroke
				(width 0.1)
				(type default)
			)
			(layer "F.Fab")
		)
		(fp_line
			(start 0.67945 0.3048)
			(end 0.120396 0.3048)
			(stroke
				(width 0.1)
				(type default)
			)
			(layer "F.Fab")
		)
		(pad "1" smd circle
			(at -0.40005 0)
			(size 0 0)
			(layers "F.Cu" "F.Mask" "F.Paste")
			(net "P3V3_AUX")
		)
		(pad "2" smd circle
			(at 0.40005 0)
			(size 0 0)
			(layers "F.Cu" "F.Mask" "F.Paste")
			(net "FM_P2E_BUF2_VOD_SEL")
		)
	)
	(footprint ""
		(layer "F.Cu")
		(at 329.40625 -347.580458 90)
		(property "Reference" "PR1773"
			(at 0 0 90)
			(layer "F.SilkS")
			(hide yes)
			(effects
				(font
					(size 1.27 1.27)
				)
			)
		)
		(property "Value" ""
			(at 0 0 90)
			(layer "F.Fab")
			(effects
				(font
					(size 1.27 1.27)
				)
			)
		)
		(duplicate_pad_numbers_are_jumpers no)
		(fp_line
			(start 0.7874 -0.4064)
			(end 0.7874 0.4064)
			(stroke
				(width 0.1524)
				(type default)
			)
			(layer "F.SilkS")
		)
		(fp_line
			(start -0.7874 -0.4064)
			(end 0.7874 -0.4064)
			(stroke
				(width 0.1524)
				(type default)
			)
			(layer "F.SilkS")
		)
		(fp_line
			(start 0.7874 0.4064)
			(end -0.7874 0.4064)
			(stroke
				(width 0.1524)
				(type default)
			)
			(layer "F.SilkS")
		)
		(fp_line
			(start -0.7874 0.4064)
			(end -0.7874 -0.4064)
			(stroke
				(width 0.1524)
				(type default)
			)
			(layer "F.SilkS")
		)
		(fp_line
			(start -0.12065 -0.305054)
			(end -0.12065 -0.2794)
			(stroke
				(width 0.1)
				(type default)
			)
			(layer "F.Fab")
		)
		(fp_line
			(start -0.67945 -0.305054)
			(end -0.12065 -0.305054)
			(stroke
				(width 0.1)
				(type default)
			)
			(layer "F.Fab")
		)
		(fp_line
			(start 0.67945 -0.3048)
			(end 0.67945 0.3048)
			(stroke
				(width 0.1)
				(type default)
			)
			(layer "F.Fab")
		)
		(fp_line
			(start 0.12065 -0.3048)
			(end 0.67945 -0.3048)
			(stroke
				(width 0.1)
				(type default)
			)
			(layer "F.Fab")
		)
		(fp_line
			(start 0.12065 -0.2794)
			(end 0.12065 -0.3048)
			(stroke
				(width 0.1)
				(type default)
			)
			(layer "F.Fab")
		)
		(fp_line
			(start -0.12065 -0.2794)
			(end 0.12065 -0.2794)
			(stroke
				(width 0.1)
				(type default)
			)
			(layer "F.Fab")
		)
		(fp_line
			(start 0.120396 0.2794)
			(end -0.12065 0.2794)
			(stroke
				(width 0.1)
				(type default)
			)
			(layer "F.Fab")
		)
		(fp_line
			(start -0.12065 0.2794)
			(end -0.12065 0.3048)
			(stroke
				(width 0.1)
				(type default)
			)
			(layer "F.Fab")
		)
		(fp_line
			(start 0.67945 0.3048)
			(end 0.120396 0.3048)
			(stroke
				(width 0.1)
				(type default)
			)
			(layer "F.Fab")
		)
		(fp_line
			(start 0.120396 0.3048)
			(end 0.120396 0.2794)
			(stroke
				(width 0.1)
				(type default)
			)
			(layer "F.Fab")
		)
		(fp_line
			(start -0.12065 0.3048)
			(end -0.67945 0.3048)
			(stroke
				(width 0.1)
				(type default)
			)
			(layer "F.Fab")
		)
		(fp_line
			(start -0.67945 0.3048)
			(end -0.67945 -0.305054)
			(stroke
				(width 0.1)
				(type default)
			)
			(layer "F.Fab")
		)
		(pad "1" smd circle
			(at -0.40005 0 90)
			(size 0 0)
			(layers "F.Cu" "F.Mask" "F.Paste")
			(net "SW_PVCCIN_CPU0_BOOT7")
		)
		(pad "2" smd circle
			(at 0.40005 0 90)
			(size 0 0)
			(layers "F.Cu" "F.Mask" "F.Paste")
			(net "SW_PVCCIN_CPU0_BOOT7_R")
		)
	)
	(footprint ""
		(layer "F.Cu")
		(at 430.600104 -134.494778)
		(property "Reference" "C3274"
			(at 0 0 0)
			(layer "F.SilkS")
			(hide yes)
			(effects
				(font
					(size 1.27 1.27)
				)
			)
		)
		(property "Value" ""
			(at 0 0 0)
			(layer "F.Fab")
			(effects
				(font
					(size 1.27 1.27)
				)
			)
		)
		(duplicate_pad_numbers_are_jumpers no)
		(fp_line
			(start -0.7874 -0.4064)
			(end 0.7874 -0.4064)
			(stroke
				(width 0.1524)
				(type default)
			)
			(layer "F.SilkS")
		)
		(fp_line
			(start -0.7874 0.4064)
			(end -0.7874 -0.4064)
			(stroke
				(width 0.1524)
				(type default)
			)
			(layer "F.SilkS")
		)
		(fp_line
			(start 0.7874 -0.4064)
			(end 0.7874 0.4064)
			(stroke
				(width 0.1524)
				(type default)
			)
			(layer "F.SilkS")
		)
		(fp_line
			(start 0.7874 0.4064)
			(end -0.7874 0.4064)
			(stroke
				(width 0.1524)
				(type default)
			)
			(layer "F.SilkS")
		)
		(fp_line
			(start -0.67945 -0.305054)
			(end -0.12065 -0.305054)
			(stroke
				(width 0.1)
				(type default)
			)
			(layer "F.Fab")
		)
		(fp_line
			(start -0.67945 0.3048)
			(end -0.67945 -0.305054)
			(stroke
				(width 0.1)
				(type default)
			)
			(layer "F.Fab")
		)
		(fp_line
			(start -0.12065 -0.305054)
			(end -0.12065 -0.2794)
			(stroke
				(width 0.1)
				(type default)
			)
			(layer "F.Fab")
		)
		(fp_line
			(start -0.12065 -0.2794)
			(end 0.12065 -0.2794)
			(stroke
				(width 0.1)
				(type default)
			)
			(layer "F.Fab")
		)
		(fp_line
			(start -0.12065 0.2794)
			(end -0.12065 0.3048)
			(stroke
				(width 0.1)
				(type default)
			)
			(layer "F.Fab")
		)
		(fp_line
			(start -0.12065 0.3048)
			(end -0.67945 0.3048)
			(stroke
				(width 0.1)
				(type default)
			)
			(layer "F.Fab")
		)
		(fp_line
			(start 0.120396 0.2794)
			(end -0.12065 0.2794)
			(stroke
				(width 0.1)
				(type default)
			)
			(layer "F.Fab")
		)
		(fp_line
			(start 0.120396 0.3048)
			(end 0.120396 0.2794)
			(stroke
				(width 0.1)
				(type default)
			)
			(layer "F.Fab")
		)
		(fp_line
			(start 0.12065 -0.3048)
			(end 0.67945 -0.3048)
			(stroke
				(width 0.1)
				(type default)
			)
			(layer "F.Fab")
		)
		(fp_line
			(start 0.12065 -0.2794)
			(end 0.12065 -0.3048)
			(stroke
				(width 0.1)
				(type default)
			)
			(layer "F.Fab")
		)
		(fp_line
			(start 0.67945 -0.3048)
			(end 0.67945 0.3048)
			(stroke
				(width 0.1)
				(type default)
			)
			(layer "F.Fab")
		)
		(fp_line
			(start 0.67945 0.3048)
			(end 0.120396 0.3048)
			(stroke
				(width 0.1)
				(type default)
			)
			(layer "F.Fab")
		)
		(pad "1" smd circle
			(at -0.40005 0)
			(size 0 0)
			(layers "F.Cu" "F.Mask" "F.Paste")
			(net "PVCCINFAON_CPU0_EN_R")
		)
		(pad "2" smd circle
			(at 0.40005 0)
			(size 0 0)
			(layers "F.Cu" "F.Mask" "F.Paste")
			(net "GND")
		)
	)
	(footprint ""
		(layer "F.Cu")
		(at 19.812 -410.7942 90)
		(property "Reference" "R4729"
			(at 0 0 90)
			(layer "F.SilkS")
			(hide yes)
			(effects
				(font
					(size 1.27 1.27)
				)
			)
		)
		(property "Value" ""
			(at 0 0 90)
			(layer "F.Fab")
			(effects
				(font
					(size 1.27 1.27)
				)
			)
		)
		(duplicate_pad_numbers_are_jumpers no)
		(fp_line
			(start 0.7874 -0.4064)
			(end 0.7874 0.4064)
			(stroke
				(width 0.1524)
				(type default)
			)
			(layer "F.SilkS")
		)
		(fp_line
			(start -0.7874 -0.4064)
			(end 0.7874 -0.4064)
			(stroke
				(width 0.1524)
				(type default)
			)
			(layer "F.SilkS")
		)
		(fp_line
			(start 0.7874 0.4064)
			(end -0.7874 0.4064)
			(stroke
				(width 0.1524)
				(type default)
			)
			(layer "F.SilkS")
		)
		(fp_line
			(start -0.7874 0.4064)
			(end -0.7874 -0.4064)
			(stroke
				(width 0.1524)
				(type default)
			)
			(layer "F.SilkS")
		)
		(fp_line
			(start -0.12065 -0.305054)
			(end -0.12065 -0.2794)
			(stroke
				(width 0.1)
				(type default)
			)
			(layer "F.Fab")
		)
		(fp_line
			(start -0.67945 -0.305054)
			(end -0.12065 -0.305054)
			(stroke
				(width 0.1)
				(type default)
			)
			(layer "F.Fab")
		)
		(fp_line
			(start 0.67945 -0.3048)
			(end 0.67945 0.3048)
			(stroke
				(width 0.1)
				(type default)
			)
			(layer "F.Fab")
		)
		(fp_line
			(start 0.12065 -0.3048)
			(end 0.67945 -0.3048)
			(stroke
				(width 0.1)
				(type default)
			)
			(layer "F.Fab")
		)
		(fp_line
			(start 0.12065 -0.2794)
			(end 0.12065 -0.3048)
			(stroke
				(width 0.1)
				(type default)
			)
			(layer "F.Fab")
		)
		(fp_line
			(start -0.12065 -0.2794)
			(end 0.12065 -0.2794)
			(stroke
				(width 0.1)
				(type default)
			)
			(layer "F.Fab")
		)
		(fp_line
			(start 0.120396 0.2794)
			(end -0.12065 0.2794)
			(stroke
				(width 0.1)
				(type default)
			)
			(layer "F.Fab")
		)
		(fp_line
			(start -0.12065 0.2794)
			(end -0.12065 0.3048)
			(stroke
				(width 0.1)
				(type default)
			)
			(layer "F.Fab")
		)
		(fp_line
			(start 0.67945 0.3048)
			(end 0.120396 0.3048)
			(stroke
				(width 0.1)
				(type default)
			)
			(layer "F.Fab")
		)
		(fp_line
			(start 0.120396 0.3048)
			(end 0.120396 0.2794)
			(stroke
				(width 0.1)
				(type default)
			)
			(layer "F.Fab")
		)
		(fp_line
			(start -0.12065 0.3048)
			(end -0.67945 0.3048)
			(stroke
				(width 0.1)
				(type default)
			)
			(layer "F.Fab")
		)
		(fp_line
			(start -0.67945 0.3048)
			(end -0.67945 -0.305054)
			(stroke
				(width 0.1)
				(type default)
			)
			(layer "F.Fab")
		)
		(pad "1" smd circle
			(at -0.40005 0 90)
			(size 0 0)
			(layers "F.Cu" "F.Mask" "F.Paste")
			(net "GPU_PRSNT_N_ISO")
		)
		(pad "2" smd circle
			(at 0.40005 0 90)
			(size 0 0)
			(layers "F.Cu" "F.Mask" "F.Paste")
			(net "GPU_PRSNT_N_ISO_R1")
		)
	)
	(footprint ""
		(layer "F.Cu")
		(at 104.8258 -410.2608 180)
		(property "Reference" "R4724"
			(at 0 0 180)
			(layer "F.SilkS")
			(hide yes)
			(effects
				(font
					(size 1.27 1.27)
				)
			)
		)
		(property "Value" ""
			(at 0 0 180)
			(layer "F.Fab")
			(effects
				(font
					(size 1.27 1.27)
				)
			)
		)
		(duplicate_pad_numbers_are_jumpers no)
		(fp_line
			(start 0.7874 0.4064)
			(end -0.7874 0.4064)
			(stroke
				(width 0.1524)
				(type default)
			)
			(layer "F.SilkS")
		)
		(fp_line
			(start 0.7874 -0.4064)
			(end 0.7874 0.4064)
			(stroke
				(width 0.1524)
				(type default)
			)
			(layer "F.SilkS")
		)
		(fp_line
			(start -0.7874 0.4064)
			(end -0.7874 -0.4064)
			(stroke
				(width 0.1524)
				(type default)
			)
			(layer "F.SilkS")
		)
		(fp_line
			(start -0.7874 -0.4064)
			(end 0.7874 -0.4064)
			(stroke
				(width 0.1524)
				(type default)
			)
			(layer "F.SilkS")
		)
		(fp_line
			(start 0.67945 0.3048)
			(end 0.120396 0.3048)
			(stroke
				(width 0.1)
				(type default)
			)
			(layer "F.Fab")
		)
		(fp_line
			(start 0.67945 -0.3048)
			(end 0.67945 0.3048)
			(stroke
				(width 0.1)
				(type default)
			)
			(layer "F.Fab")
		)
		(fp_line
			(start 0.12065 -0.2794)
			(end 0.12065 -0.3048)
			(stroke
				(width 0.1)
				(type default)
			)
			(layer "F.Fab")
		)
		(fp_line
			(start 0.12065 -0.3048)
			(end 0.67945 -0.3048)
			(stroke
				(width 0.1)
				(type default)
			)
			(layer "F.Fab")
		)
		(fp_line
			(start 0.120396 0.3048)
			(end 0.120396 0.2794)
			(stroke
				(width 0.1)
				(type default)
			)
			(layer "F.Fab")
		)
		(fp_line
			(start 0.120396 0.2794)
			(end -0.12065 0.2794)
			(stroke
				(width 0.1)
				(type default)
			)
			(layer "F.Fab")
		)
		(fp_line
			(start -0.12065 0.3048)
			(end -0.67945 0.3048)
			(stroke
				(width 0.1)
				(type default)
			)
			(layer "F.Fab")
		)
		(fp_line
			(start -0.12065 0.2794)
			(end -0.12065 0.3048)
			(stroke
				(width 0.1)
				(type default)
			)
			(layer "F.Fab")
		)
		(fp_line
			(start -0.12065 -0.2794)
			(end 0.12065 -0.2794)
			(stroke
				(width 0.1)
				(type default)
			)
			(layer "F.Fab")
		)
		(fp_line
			(start -0.12065 -0.305054)
			(end -0.12065 -0.2794)
			(stroke
				(width 0.1)
				(type default)
			)
			(layer "F.Fab")
		)
		(fp_line
			(start -0.67945 0.3048)
			(end -0.67945 -0.305054)
			(stroke
				(width 0.1)
				(type default)
			)
			(layer "F.Fab")
		)
		(fp_line
			(start -0.67945 -0.305054)
			(end -0.12065 -0.305054)
			(stroke
				(width 0.1)
				(type default)
			)
			(layer "F.Fab")
		)
		(pad "1" smd circle
			(at -0.40005 0 180)
			(size 0 0)
			(layers "F.Cu" "F.Mask" "F.Paste")
			(net "PRSNT_SWB_N")
		)
		(pad "2" smd circle
			(at 0.40005 0 180)
			(size 0 0)
			(layers "F.Cu" "F.Mask" "F.Paste")
			(net "GND")
		)
	)
	(footprint ""
		(layer "F.Cu")
		(at 123.192794 -402.371052 -90)
		(property "Reference" "C745"
			(at 0 0 270)
			(layer "F.SilkS")
			(hide yes)
			(effects
				(font
					(size 1.27 1.27)
				)
			)
		)
		(property "Value" ""
			(at 0 0 270)
			(layer "F.Fab")
			(effects
				(font
					(size 1.27 1.27)
				)
			)
		)
		(duplicate_pad_numbers_are_jumpers no)
		(fp_line
			(start -0.299974 0.150114)
			(end -0.299974 -0.150114)
			(stroke
				(width 0.1)
				(type default)
			)
			(layer "F.Fab")
		)
		(fp_line
			(start 0.299974 0.150114)
			(end -0.299974 0.150114)
			(stroke
				(width 0.1)
				(type default)
			)
			(layer "F.Fab")
		)
		(fp_line
			(start -0.299974 -0.150114)
			(end 0.299974 -0.150114)
			(stroke
				(width 0.1)
				(type default)
			)
			(layer "F.Fab")
		)
		(fp_line
			(start 0.299974 -0.150114)
			(end 0.299974 0.150114)
			(stroke
				(width 0.1)
				(type default)
			)
			(layer "F.Fab")
		)
		(pad "1" smd rect
			(at -0.2667 0 270)
			(size 0.3048 0.381)
			(layers "F.Cu" "F.Mask" "F.Paste")
			(net "P5E_CPU1_PE2_TX_C_DP<14>")
		)
		(pad "2" smd rect
			(at 0.2667 0 270)
			(size 0.3048 0.381)
			(layers "F.Cu" "F.Mask" "F.Paste")
			(net "P5E_CPU1_PE2_TX_DP<14>")
		)
	)
	(footprint ""
		(layer "F.Cu")
		(at 290.457382 -375.745502)
		(property "Reference" "PC1653"
			(at 0 0 0)
			(layer "F.SilkS")
			(hide yes)
			(effects
				(font
					(size 1.27 1.27)
				)
			)
		)
		(property "Value" ""
			(at 0 0 0)
			(layer "F.Fab")
			(effects
				(font
					(size 1.27 1.27)
				)
			)
		)
		(duplicate_pad_numbers_are_jumpers no)
		(fp_line
			(start -0.7874 -0.4064)
			(end 0.7874 -0.4064)
			(stroke
				(width 0.1524)
				(type default)
			)
			(layer "F.SilkS")
		)
		(fp_line
			(start -0.7874 0.4064)
			(end -0.7874 -0.4064)
			(stroke
				(width 0.1524)
				(type default)
			)
			(layer "F.SilkS")
		)
		(fp_line
			(start 0.7874 -0.4064)
			(end 0.7874 0.4064)
			(stroke
				(width 0.1524)
				(type default)
			)
			(layer "F.SilkS")
		)
		(fp_line
			(start 0.7874 0.4064)
			(end -0.7874 0.4064)
			(stroke
				(width 0.1524)
				(type default)
			)
			(layer "F.SilkS")
		)
		(fp_line
			(start -0.67945 -0.305054)
			(end -0.12065 -0.305054)
			(stroke
				(width 0.1)
				(type default)
			)
			(layer "F.Fab")
		)
		(fp_line
			(start -0.67945 0.3048)
			(end -0.67945 -0.305054)
			(stroke
				(width 0.1)
				(type default)
			)
			(layer "F.Fab")
		)
		(fp_line
			(start -0.12065 -0.305054)
			(end -0.12065 -0.2794)
			(stroke
				(width 0.1)
				(type default)
			)
			(layer "F.Fab")
		)
		(fp_line
			(start -0.12065 -0.2794)
			(end 0.12065 -0.2794)
			(stroke
				(width 0.1)
				(type default)
			)
			(layer "F.Fab")
		)
		(fp_line
			(start -0.12065 0.2794)
			(end -0.12065 0.3048)
			(stroke
				(width 0.1)
				(type default)
			)
			(layer "F.Fab")
		)
		(fp_line
			(start -0.12065 0.3048)
			(end -0.67945 0.3048)
			(stroke
				(width 0.1)
				(type default)
			)
			(layer "F.Fab")
		)
		(fp_line
			(start 0.120396 0.2794)
			(end -0.12065 0.2794)
			(stroke
				(width 0.1)
				(type default)
			)
			(layer "F.Fab")
		)
		(fp_line
			(start 0.120396 0.3048)
			(end 0.120396 0.2794)
			(stroke
				(width 0.1)
				(type default)
			)
			(layer "F.Fab")
		)
		(fp_line
			(start 0.12065 -0.3048)
			(end 0.67945 -0.3048)
			(stroke
				(width 0.1)
				(type default)
			)
			(layer "F.Fab")
		)
		(fp_line
			(start 0.12065 -0.2794)
			(end 0.12065 -0.3048)
			(stroke
				(width 0.1)
				(type default)
			)
			(layer "F.Fab")
		)
		(fp_line
			(start 0.67945 -0.3048)
			(end 0.67945 0.3048)
			(stroke
				(width 0.1)
				(type default)
			)
			(layer "F.Fab")
		)
		(fp_line
			(start 0.67945 0.3048)
			(end 0.120396 0.3048)
			(stroke
				(width 0.1)
				(type default)
			)
			(layer "F.Fab")
		)
		(pad "1" smd circle
			(at -0.40005 0)
			(size 0 0)
			(layers "F.Cu" "F.Mask" "F.Paste")
			(net "P12V_AUX")
		)
		(pad "2" smd circle
			(at 0.40005 0)
			(size 0 0)
			(layers "F.Cu" "F.Mask" "F.Paste")
			(net "GND")
		)
	)
)
